# S9S_MB_2U (Grand Teton) — schematic netlist excerpt (pin names and nets, part order shuffled) for the footprints in the layout excerpt that follows; sources: Cadence DE-HDL packaged netlist, KiCad conversion of 03242023_DA0F0TMBIJ0_F0T_Motherboard_J_brd_V01_OCP.brd

PC1189  Q_CAPP  270UF 16V 20% OSCON  pkg THLF  page 272 : A = SW_P12V_PVCCFA_EHV_FIVRA_CPU0_R ; B = GND
R3085  Q_RES  130 1% CHIP  pkg 0402LF  page 256 : A = LED_RST_PLD_CPU1_DRAM_GH_N ; B = P3V3_AUX
R3455  Q_RES  10K 1% CHIP  pkg 0402LF  page 149 : A = RST_PERST_1_SWB_BUF_R_N ; B = GND

(kicad_pcb
	(version 20260206)
	(generator "pcbnew")
	(generator_version "10.0")
	(general
		(thickness 1.6)
		(legacy_teardrops no)
	)
	(paper "A4")
	(title_block
		(title "03242023_DA0F0TMBIJ0_F0T_Motherboard_J_brd_V01_OCP.brd")
		(comment 1 "Grand Teton / footprints 729-731 of 6105")
	)
	(layers
		(0 "F.Cu" signal "TOP")
		(4 "In1.Cu" signal "GND")
		(6 "In2.Cu" signal "IN1")
		(8 "In3.Cu" signal "GND1")
		(10 "In4.Cu" signal "IN2")
		(12 "In5.Cu" signal "GND2")
		(14 "In6.Cu" signal "IN3")
		(16 "In7.Cu" signal "GND3")
		(18 "In8.Cu" signal "VCC")
		(20 "In9.Cu" signal "VCC1")
		(22 "In10.Cu" signal "GND4")
		(24 "In11.Cu" signal "IN4")
		(26 "In12.Cu" signal "GND5")
		(28 "In13.Cu" signal "IN5")
		(30 "In14.Cu" signal "GND6")
		(32 "In15.Cu" signal "IN6")
		(34 "In16.Cu" signal "GND7")
		(2 "B.Cu" signal "BOTTOM")
		(9 "F.Adhes" user "F.Adhesive")
		(11 "B.Adhes" user "B.Adhesive")
		(13 "F.Paste" user "Package Geometry/Pastemask Top")
		(15 "B.Paste" user "Package Geometry/Pastemask Bottom")
		(5 "F.SilkS" user "Ref Des/Silkscreen Top")
		(7 "B.SilkS" user "Ref Des/Silkscreen Bottom")
		(1 "F.Mask" user "Board Geometry/Soldermask Top")
		(3 "B.Mask" user "Board Geometry/Soldermask Bottom")
		(17 "Dwgs.User" user "User.Drawings")
		(19 "Cmts.User" user "User.Comments")
		(21 "Eco1.User" user "User.Eco1")
		(23 "Eco2.User" user "User.Eco2")
		(25 "Edge.Cuts" user "Board Geometry/Outline")
		(27 "Margin" user)
		(31 "F.CrtYd" user "Package Geometry/Place Bound Top")
		(29 "B.CrtYd" user "Package Geometry/Place Bound Bottom")
		(35 "F.Fab" user "Ref Des/Assembly Top")
		(33 "B.Fab" user "Ref Des/Assembly Bottom")
	)
	(footprint ""
		(layer "F.Cu")
		(at 31.29788 -424.271948)
		(property "Reference" "R3455"
			(at 0 0 0)
			(layer "F.SilkS")
			(hide yes)
			(effects
				(font
					(size 1.27 1.27)
				)
			)
		)
		(property "Value" ""
			(at 0 0 0)
			(layer "F.Fab")
			(effects
				(font
					(size 1.27 1.27)
				)
			)
		)
		(duplicate_pad_numbers_are_jumpers no)
		(fp_line
			(start -0.7874 -0.4064)
			(end 0.7874 -0.4064)
			(stroke
				(width 0.1524)
				(type default)
			)
			(layer "F.SilkS")
		)
		(fp_line
			(start -0.7874 0.4064)
			(end -0.7874 -0.4064)
			(stroke
				(width 0.1524)
				(type default)
			)
			(layer "F.SilkS")
		)
		(fp_line
			(start 0.7874 -0.4064)
			(end 0.7874 0.4064)
			(stroke
				(width 0.1524)
				(type default)
			)
			(layer "F.SilkS")
		)
		(fp_line
			(start 0.7874 0.4064)
			(end -0.7874 0.4064)
			(stroke
				(width 0.1524)
				(type default)
			)
			(layer "F.SilkS")
		)
		(fp_line
			(start -0.67945 -0.305054)
			(end -0.12065 -0.305054)
			(stroke
				(width 0.1)
				(type default)
			)
			(layer "F.Fab")
		)
		(fp_line
			(start -0.67945 0.3048)
			(end -0.67945 -0.305054)
			(stroke
				(width 0.1)
				(type default)
			)
			(layer "F.Fab")
		)
		(fp_line
			(start -0.12065 -0.305054)
			(end -0.12065 -0.2794)
			(stroke
				(width 0.1)
				(type default)
			)
			(layer "F.Fab")
		)
		(fp_line
			(start -0.12065 -0.2794)
			(end 0.12065 -0.2794)
			(stroke
				(width 0.1)
				(type default)
			)
			(layer "F.Fab")
		)
		(fp_line
			(start -0.12065 0.2794)
			(end -0.12065 0.3048)
			(stroke
				(width 0.1)
				(type default)
			)
			(layer "F.Fab")
		)
		(fp_line
			(start -0.12065 0.3048)
			(end -0.67945 0.3048)
			(stroke
				(width 0.1)
				(type default)
			)
			(layer "F.Fab")
		)
		(fp_line
			(start 0.120396 0.2794)
			(end -0.12065 0.2794)
			(stroke
				(width 0.1)
				(type default)
			)
			(layer "F.Fab")
		)
		(fp_line
			(start 0.120396 0.3048)
			(end 0.120396 0.2794)
			(stroke
				(width 0.1)
				(type default)
			)
			(layer "F.Fab")
		)
		(fp_line
			(start 0.12065 -0.3048)
			(end 0.67945 -0.3048)
			(stroke
				(width 0.1)
				(type default)
			)
			(layer "F.Fab")
		)
		(fp_line
			(start 0.12065 -0.2794)
			(end 0.12065 -0.3048)
			(stroke
				(width 0.1)
				(type default)
			)
			(layer "F.Fab")
		)
		(fp_line
			(start 0.67945 -0.3048)
			(end 0.67945 0.3048)
			(stroke
				(width 0.1)
				(type default)
			)
			(layer "F.Fab")
		)
		(fp_line
			(start 0.67945 0.3048)
			(end 0.120396 0.3048)
			(stroke
				(width 0.1)
				(type default)
			)
			(layer "F.Fab")
		)
		(pad "1" smd circle
			(at -0.40005 0)
			(size 0 0)
			(layers "F.Cu" "F.Mask" "F.Paste")
			(net "RST_PERST_1_SWB_BUF_R_N")
		)
		(pad "2" smd circle
			(at 0.40005 0)
			(size 0 0)
			(layers "F.Cu" "F.Mask" "F.Paste")
			(net "GND")
		)
	)
	(footprint ""
		(layer "F.Cu")
		(at 424.205654 -371.76837 90)
		(property "Reference" "PC1189"
			(at 0 0 90)
			(layer "F.SilkS")
			(hide yes)
			(effects
				(font
					(size 1.27 1.27)
				)
			)
		)
		(property "Value" ""
			(at 0 0 90)
			(layer "F.Fab")
			(effects
				(font
					(size 1.27 1.27)
				)
			)
		)
		(duplicate_pad_numbers_are_jumpers no)
		(fp_line
			(start -3.400044 1.249934)
			(end 3.400044 1.249934)
			(stroke
				(width 0.1524)
				(type default)
			)
			(layer "F.SilkS")
		)
		(fp_circle
			(center 0 1.249934)
			(end 0 4.649978)
			(stroke
				(width 0.1524)
				(type default)
			)
			(fill no)
			(layer "F.SilkS")
		)
		(fp_poly
			(pts
				(arc
					(start -3.400044 1.249934)
					(mid 0 4.649978)
					(end 3.400044 1.249934)
				)
			)
			(stroke
				(width 0)
				(type default)
			)
			(fill yes)
			(layer "F.SilkS")
		)
		(fp_circle
			(center 0 1.249934)
			(end 0 4.649978)
			(stroke
				(width 0.1)
				(type default)
			)
			(fill no)
			(layer "F.Fab")
		)
		(pad "1" thru_hole rect
			(at 0 0 90)
			(size 1.524 1.524)
			(drill 1.016)
			(layers "*.Cu" "*.Mask")
			(remove_unused_layers no)
			(net "SW_P12V_PVCCFA_EHV_FIVRA_CPU0_R")
			(clearance 0)
			(padstack
				(mode front_inner_back)
				(layer "Inner"
					(shape circle)
					(size 1.524 1.524)
					(clearance 0)
				)
				(layer "B.Cu"
					(shape rect)
					(size 1.524 1.524)
					(clearance 0)
				)
			)
		)
		(pad "2" thru_hole circle
			(at 0 2.500122 90)
			(size 1.524 1.524)
			(drill 1.016)
			(layers "*.Cu" "*.Mask")
			(remove_unused_layers no)
			(net "GND")
			(clearance 0)
		)
	)
	(footprint ""
		(layer "F.Cu")
		(at 68.010786 -65.082674 -90)
		(property "Reference" "R3085"
			(at 0 0 270)
			(layer "F.SilkS")
			(hide yes)
			(effects
				(font
					(size 1.27 1.27)
				)
			)
		)
		(property "Value" ""
			(at 0 0 270)
			(layer "F.Fab")
			(effects
				(font
					(size 1.27 1.27)
				)
			)
		)
		(duplicate_pad_numbers_are_jumpers no)
		(fp_line
			(start -0.7874 0.4064)
			(end -0.7874 -0.4064)
			(stroke
				(width 0.1524)
				(type default)
			)
			(layer "F.SilkS")
		)
		(fp_line
			(start 0.7874 0.4064)
			(end -0.7874 0.4064)
			(stroke
				(width 0.1524)
				(type default)
			)
			(layer "F.SilkS")
		)
		(fp_line
			(start -0.7874 -0.4064)
			(end 0.7874 -0.4064)
			(stroke
				(width 0.1524)
				(type default)
			)
			(layer "F.SilkS")
		)
		(fp_line
			(start 0.7874 -0.4064)
			(end 0.7874 0.4064)
			(stroke
				(width 0.1524)
				(type default)
			)
			(layer "F.SilkS")
		)
		(fp_line
			(start -0.67945 0.3048)
			(end -0.67945 -0.305054)
			(stroke
				(width 0.1)
				(type default)
			)
			(layer "F.Fab")
		)
		(fp_line
			(start -0.12065 0.3048)
			(end -0.67945 0.3048)
			(stroke
				(width 0.1)
				(type default)
			)
			(layer "F.Fab")
		)
		(fp_line
			(start 0.120396 0.3048)
			(end 0.120396 0.2794)
			(stroke
				(width 0.1)
				(type default)
			)
			(layer "F.Fab")
		)
		(fp_line
			(start 0.67945 0.3048)
			(end 0.120396 0.3048)
			(stroke
				(width 0.1)
				(type default)
			)
			(layer "F.Fab")
		)
		(fp_line
			(start -0.12065 0.2794)
			(end -0.12065 0.3048)
			(stroke
				(width 0.1)
				(type default)
			)
			(layer "F.Fab")
		)
		(fp_line
			(start 0.120396 0.2794)
			(end -0.12065 0.2794)
			(stroke
				(width 0.1)
				(type default)
			)
			(layer "F.Fab")
		)
		(fp_line
			(start -0.12065 -0.2794)
			(end 0.12065 -0.2794)
			(stroke
				(width 0.1)
				(type default)
			)
			(layer "F.Fab")
		)
		(fp_line
			(start 0.12065 -0.2794)
			(end 0.12065 -0.3048)
			(stroke
				(width 0.1)
				(type default)
			)
			(layer "F.Fab")
		)
		(fp_line
			(start 0.12065 -0.3048)
			(end 0.67945 -0.3048)
			(stroke
				(width 0.1)
				(type default)
			)
			(layer "F.Fab")
		)
		(fp_line
			(start 0.67945 -0.3048)
			(end 0.67945 0.3048)
			(stroke
				(width 0.1)
				(type default)
			)
			(layer "F.Fab")
		)
		(fp_line
			(start -0.67945 -0.305054)
			(end -0.12065 -0.305054)
			(stroke
				(width 0.1)
				(type default)
			)
			(layer "F.Fab")
		)
		(fp_line
			(start -0.12065 -0.305054)
			(end -0.12065 -0.2794)
			(stroke
				(width 0.1)
				(type default)
			)
			(layer "F.Fab")
		)
		(pad "1" smd circle
			(at -0.40005 0 270)
			(size 0 0)
			(layers "F.Cu" "F.Mask" "F.Paste")
			(net "LED_RST_PLD_CPU1_DRAM_GH_N")
		)
		(pad "2" smd circle
			(at 0.40005 0 270)
			(size 0 0)
			(layers "F.Cu" "F.Mask" "F.Paste")
			(net "P3V3_AUX")
		)
	)
)
